(kicad_pcb
	(version 20260206)
	(generator "pcbnew")
	(generator_version "10.0")
	(general
		(thickness 1.6)
		(legacy_teardrops no)
	)
	(paper "A4")
	(title_block
		(title "01162023_DA0F0TEBIF0_F0T_Expander_BD_F_brd_V02_OCP.brd")
		(comment 1 "Grand Teton / footprints 3827-3832 of 9728")
	)
	(layers
		(0 "F.Cu" signal "TOP")
		(4 "In1.Cu" signal "GND")
		(6 "In2.Cu" signal "VCC")
		(8 "In3.Cu" signal "VCC1")
		(10 "In4.Cu" signal "GND1")
		(12 "In5.Cu" signal "IN1")
		(14 "In6.Cu" signal "GND2")
		(16 "In7.Cu" signal "IN2")
		(18 "In8.Cu" signal "GND3")
		(20 "In9.Cu" signal "IN3")
		(22 "In10.Cu" signal "GND4")
		(24 "In11.Cu" signal "IN4")
		(26 "In12.Cu" signal "GND5")
		(28 "In13.Cu" signal "IN5")
		(30 "In14.Cu" signal "GND6")
		(32 "In15.Cu" signal "IN6")
		(34 "In16.Cu" signal "GND7")
		(2 "B.Cu" signal "BOTTOM")
		(9 "F.Adhes" user "F.Adhesive")
		(11 "B.Adhes" user "B.Adhesive")
		(13 "F.Paste" user "Package Geometry/Pastemask Top")
		(15 "B.Paste" user "Package Geometry/Pastemask Bottom")
		(5 "F.SilkS" user "Ref Des/Silkscreen Top")
		(7 "B.SilkS" user "Ref Des/Silkscreen Bottom")
		(1 "F.Mask" user "Board Geometry/Soldermask Top")
		(3 "B.Mask" user "Board Geometry/Soldermask Bottom")
		(17 "Dwgs.User" user "User.Drawings")
		(19 "Cmts.User" user "User.Comments")
		(21 "Eco1.User" user "User.Eco1")
		(23 "Eco2.User" user "User.Eco2")
		(25 "Edge.Cuts" user "Board Geometry/Outline")
		(27 "Margin" user)
		(31 "F.CrtYd" user "Package Geometry/Place Bound Top")
		(29 "B.CrtYd" user "Package Geometry/Place Bound Bottom")
		(35 "F.Fab" user "Ref Des/Assembly Top")
		(33 "B.Fab" user "Ref Des/Assembly Bottom")
	)
	(footprint ""
		(layer "F.Cu")
		(at 419.546786 -37.47516)
		(property "Reference" "R6123"
			(at 0 0 0)
			(layer "F.SilkS")
			(hide yes)
			(effects
				(font
					(size 1.27 1.27)
				)
			)
		)
		(property "Value" ""
			(at 0 0 0)
			(layer "F.Fab")
			(effects
				(font
					(size 1.27 1.27)
				)
			)
		)
		(duplicate_pad_numbers_are_jumpers no)
		(fp_line
			(start -0.7874 -0.4064)
			(end 0.7874 -0.4064)
			(stroke
				(width 0.1524)
				(type default)
			)
			(layer "F.SilkS")
		)
		(fp_line
			(start -0.7874 0.4064)
			(end -0.7874 -0.4064)
			(stroke
				(width 0.1524)
				(type default)
			)
			(layer "F.SilkS")
		)
		(fp_line
			(start 0.7874 -0.4064)
			(end 0.7874 0.4064)
			(stroke
				(width 0.1524)
				(type default)
			)
			(layer "F.SilkS")
		)
		(fp_line
			(start 0.7874 0.4064)
			(end -0.7874 0.4064)
			(stroke
				(width 0.1524)
				(type default)
			)
			(layer "F.SilkS")
		)
		(fp_line
			(start -0.67945 -0.305054)
			(end -0.12065 -0.305054)
			(stroke
				(width 0.1)
				(type default)
			)
			(layer "F.Fab")
		)
		(fp_line
			(start -0.67945 0.3048)
			(end -0.67945 -0.305054)
			(stroke
				(width 0.1)
				(type default)
			)
			(layer "F.Fab")
		)
		(fp_line
			(start -0.12065 -0.305054)
			(end -0.12065 -0.2794)
			(stroke
				(width 0.1)
				(type default)
			)
			(layer "F.Fab")
		)
		(fp_line
			(start -0.12065 -0.2794)
			(end 0.12065 -0.2794)
			(stroke
				(width 0.1)
				(type default)
			)
			(layer "F.Fab")
		)
		(fp_line
			(start -0.12065 0.2794)
			(end -0.12065 0.3048)
			(stroke
				(width 0.1)
				(type default)
			)
			(layer "F.Fab")
		)
		(fp_line
			(start -0.12065 0.3048)
			(end -0.67945 0.3048)
			(stroke
				(width 0.1)
				(type default)
			)
			(layer "F.Fab")
		)
		(fp_line
			(start 0.120396 0.2794)
			(end -0.12065 0.2794)
			(stroke
				(width 0.1)
				(type default)
			)
			(layer "F.Fab")
		)
		(fp_line
			(start 0.120396 0.3048)
			(end 0.120396 0.2794)
			(stroke
				(width 0.1)
				(type default)
			)
			(layer "F.Fab")
		)
		(fp_line
			(start 0.12065 -0.3048)
			(end 0.67945 -0.3048)
			(stroke
				(width 0.1)
				(type default)
			)
			(layer "F.Fab")
		)
		(fp_line
			(start 0.12065 -0.2794)
			(end 0.12065 -0.3048)
			(stroke
				(width 0.1)
				(type default)
			)
			(layer "F.Fab")
		)
		(fp_line
			(start 0.67945 -0.3048)
			(end 0.67945 0.3048)
			(stroke
				(width 0.1)
				(type default)
			)
			(layer "F.Fab")
		)
		(fp_line
			(start 0.67945 0.3048)
			(end 0.120396 0.3048)
			(stroke
				(width 0.1)
				(type default)
			)
			(layer "F.Fab")
		)
		(pad "1" smd circle
			(at -0.40005 0)
			(size 0 0)
			(layers "F.Cu" "F.Mask" "F.Paste")
			(net "P3V3_SSD15")
		)
		(pad "2" smd circle
			(at 0.40005 0)
			(size 0 0)
			(layers "F.Cu" "F.Mask" "F.Paste")
			(net "P3V3_SSD15_PG_G1")
		)
	)
	(footprint ""
		(layer "F.Cu")
		(at 146.18208 -280.189432 180)
		(property "Reference" "C3247"
			(at 0 0 180)
			(layer "F.SilkS")
			(hide yes)
			(effects
				(font
					(size 1.27 1.27)
				)
			)
		)
		(property "Value" ""
			(at 0 0 180)
			(layer "F.Fab")
			(effects
				(font
					(size 1.27 1.27)
				)
			)
		)
		(duplicate_pad_numbers_are_jumpers no)
		(fp_line
			(start 1.2954 0.5842)
			(end -1.2954 0.5842)
			(stroke
				(width 0.1524)
				(type default)
			)
			(layer "F.SilkS")
		)
		(fp_line
			(start 1.2954 -0.5842)
			(end 1.2954 0.5842)
			(stroke
				(width 0.1524)
				(type default)
			)
			(layer "F.SilkS")
		)
		(fp_line
			(start -1.2954 0.5842)
			(end -1.2954 -0.5842)
			(stroke
				(width 0.1524)
				(type default)
			)
			(layer "F.SilkS")
		)
		(fp_line
			(start -1.2954 -0.5842)
			(end 1.2954 -0.5842)
			(stroke
				(width 0.1524)
				(type default)
			)
			(layer "F.SilkS")
		)
		(fp_line
			(start 1.1938 0.4064)
			(end 0.8636 0.4064)
			(stroke
				(width 0.1)
				(type default)
			)
			(layer "F.Fab")
		)
		(fp_line
			(start 1.1938 -0.4064)
			(end 1.1938 0.4064)
			(stroke
				(width 0.1)
				(type default)
			)
			(layer "F.Fab")
		)
		(fp_line
			(start 0.8636 0.4572)
			(end -0.8636 0.4572)
			(stroke
				(width 0.1)
				(type default)
			)
			(layer "F.Fab")
		)
		(fp_line
			(start 0.8636 0.4064)
			(end 0.8636 0.4572)
			(stroke
				(width 0.1)
				(type default)
			)
			(layer "F.Fab")
		)
		(fp_line
			(start 0.8636 -0.4064)
			(end 1.1938 -0.4064)
			(stroke
				(width 0.1)
				(type default)
			)
			(layer "F.Fab")
		)
		(fp_line
			(start 0.8636 -0.4572)
			(end 0.8636 -0.4064)
			(stroke
				(width 0.1)
				(type default)
			)
			(layer "F.Fab")
		)
		(fp_line
			(start -0.8636 0.4572)
			(end -0.8636 0.4064)
			(stroke
				(width 0.1)
				(type default)
			)
			(layer "F.Fab")
		)
		(fp_line
			(start -0.8636 0.4064)
			(end -1.1938 0.4064)
			(stroke
				(width 0.1)
				(type default)
			)
			(layer "F.Fab")
		)
		(fp_line
			(start -0.8636 -0.4064)
			(end -0.8636 -0.4572)
			(stroke
				(width 0.1)
				(type default)
			)
			(layer "F.Fab")
		)
		(fp_line
			(start -0.8636 -0.4572)
			(end 0.8636 -0.4572)
			(stroke
				(width 0.1)
				(type default)
			)
			(layer "F.Fab")
		)
		(fp_line
			(start -1.1938 0.4064)
			(end -1.1938 -0.4064)
			(stroke
				(width 0.1)
				(type default)
			)
			(layer "F.Fab")
		)
		(fp_line
			(start -1.1938 -0.4064)
			(end -0.8636 -0.4064)
			(stroke
				(width 0.1)
				(type default)
			)
			(layer "F.Fab")
		)
		(pad "1" smd rect
			(at -0.7366 0 90)
			(size 0.7112 0.8128)
			(layers "F.Cu" "F.Mask" "F.Paste")
			(net "SYSPLL_VDDA18_PEX1_R")
		)
		(pad "2" smd rect
			(at 0.7366 0 90)
			(size 0.7112 0.8128)
			(layers "F.Cu" "F.Mask" "F.Paste")
			(net "GND")
		)
	)
	(footprint ""
		(layer "F.Cu")
		(at 400.910552 -18.61439 90)
		(property "Reference" "U139"
			(at -1.44399 2.341118 90)
			(unlocked yes)
			(layer "F.SilkS")
			(effects
				(font
					(size 0.7874 0.5842)
					(thickness 0.1524)
				)
				(justify left)
			)
		)
		(property "Value" ""
			(at 0 0 90)
			(layer "F.Fab")
			(effects
				(font
					(size 1.27 1.27)
				)
			)
		)
		(duplicate_pad_numbers_are_jumpers no)
		(fp_line
			(start 1.463548 -1.549908)
			(end 1.463548 1.549908)
			(stroke
				(width 0.1524)
				(type default)
			)
			(layer "F.SilkS")
		)
		(fp_line
			(start 0.762 -1.549908)
			(end 1.463548 -1.549908)
			(stroke
				(width 0.1524)
				(type default)
			)
			(layer "F.SilkS")
		)
		(fp_line
			(start -0.787908 -1.549908)
			(end 0 -0.762)
			(stroke
				(width 0.1524)
				(type default)
			)
			(layer "F.SilkS")
		)
		(fp_line
			(start -1.463548 -1.549908)
			(end -0.787908 -1.549908)
			(stroke
				(width 0.1524)
				(type default)
			)
			(layer "F.SilkS")
		)
		(fp_line
			(start 0 -0.762)
			(end 0.762 -1.549908)
			(stroke
				(width 0.1524)
				(type default)
			)
			(layer "F.SilkS")
		)
		(fp_line
			(start 1.463548 1.549908)
			(end -1.463548 1.549908)
			(stroke
				(width 0.1524)
				(type default)
			)
			(layer "F.SilkS")
		)
		(fp_line
			(start -1.463548 1.549908)
			(end -1.463548 -1.549908)
			(stroke
				(width 0.1524)
				(type default)
			)
			(layer "F.SilkS")
		)
		(fp_poly
			(pts
				(xy -3.4798 -1.359916) (xy -2.86004 -1.050036) (xy -3.4798 -0.740156)
			)
			(stroke
				(width 0)
				(type default)
			)
			(fill yes)
			(layer "F.SilkS")
		)
		(fp_line
			(start 1.549908 -1.549908)
			(end 1.549908 1.549908)
			(stroke
				(width 0.1)
				(type default)
			)
			(layer "F.Fab")
		)
		(fp_line
			(start -1.549908 -1.549908)
			(end 1.549908 -1.549908)
			(stroke
				(width 0.1)
				(type default)
			)
			(layer "F.Fab")
		)
		(fp_line
			(start 1.549908 1.549908)
			(end -1.549908 1.549908)
			(stroke
				(width 0.1)
				(type default)
			)
			(layer "F.Fab")
		)
		(fp_line
			(start -1.549908 1.549908)
			(end -1.549908 -1.549908)
			(stroke
				(width 0.1)
				(type default)
			)
			(layer "F.Fab")
		)
		(fp_poly
			(pts
				(xy -3.4798 -1.359916) (xy -2.86004 -1.050036) (xy -3.4798 -0.740156)
			)
			(stroke
				(width 0)
				(type default)
			)
			(fill yes)
			(layer "F.Fab")
		)
		(pad "1" smd rect
			(at -2.175002 -1.050036 180)
			(size 0.6096 1.1684)
			(layers "F.Cu" "F.Mask" "F.Paste")
			(net "P3V3_SSD13")
		)
		(pad "2" smd rect
			(at -2.175002 -0.32512 180)
			(size 0.4318 1.1684)
			(layers "F.Cu" "F.Mask" "F.Paste")
			(net "SMB_ISO_SSD13_SCL")
		)
		(pad "3" smd rect
			(at -2.175002 0.32512 180)
			(size 0.4318 1.1684)
			(layers "F.Cu" "F.Mask" "F.Paste")
			(net "SMB_ISO_SSD13_SDA")
		)
		(pad "4" smd rect
			(at -2.175002 1.050036 180)
			(size 0.6096 1.1684)
			(layers "F.Cu" "F.Mask" "F.Paste")
			(net "GND")
		)
		(pad "5" smd rect
			(at 2.175002 1.050036 180)
			(size 0.6096 1.1684)
			(layers "F.Cu" "F.Mask" "F.Paste")
			(net "SMB_SSD13_ISO_EN")
		)
		(pad "6" smd rect
			(at 2.175002 0.32512 180)
			(size 0.4318 1.1684)
			(layers "F.Cu" "F.Mask" "F.Paste")
			(net "SMB_BIC_I2C9_MUX1_SSD13_R_SDA")
		)
		(pad "7" smd rect
			(at 2.175002 -0.32512 180)
			(size 0.4318 1.1684)
			(layers "F.Cu" "F.Mask" "F.Paste")
			(net "SMB_BIC_I2C9_MUX1_SSD13_R_SCL")
		)
		(pad "8" smd rect
			(at 2.175002 -1.050036 180)
			(size 0.6096 1.1684)
			(layers "F.Cu" "F.Mask" "F.Paste")
			(net "P3V3_AUX")
		)
	)
	(footprint ""
		(layer "F.Cu")
		(at 365.506 -194.691 180)
		(property "Reference" "R4692"
			(at 0 0 180)
			(layer "F.SilkS")
			(hide yes)
			(effects
				(font
					(size 1.27 1.27)
				)
			)
		)
		(property "Value" ""
			(at 0 0 180)
			(layer "F.Fab")
			(effects
				(font
					(size 1.27 1.27)
				)
			)
		)
		(duplicate_pad_numbers_are_jumpers no)
		(fp_line
			(start 0.7874 0.4064)
			(end -0.7874 0.4064)
			(stroke
				(width 0.1524)
				(type default)
			)
			(layer "F.SilkS")
		)
		(fp_line
			(start 0.7874 -0.4064)
			(end 0.7874 0.4064)
			(stroke
				(width 0.1524)
				(type default)
			)
			(layer "F.SilkS")
		)
		(fp_line
			(start -0.7874 0.4064)
			(end -0.7874 -0.4064)
			(stroke
				(width 0.1524)
				(type default)
			)
			(layer "F.SilkS")
		)
		(fp_line
			(start -0.7874 -0.4064)
			(end 0.7874 -0.4064)
			(stroke
				(width 0.1524)
				(type default)
			)
			(layer "F.SilkS")
		)
		(fp_line
			(start 0.67945 0.3048)
			(end 0.120396 0.3048)
			(stroke
				(width 0.1)
				(type default)
			)
			(layer "F.Fab")
		)
		(fp_line
			(start 0.67945 -0.3048)
			(end 0.67945 0.3048)
			(stroke
				(width 0.1)
				(type default)
			)
			(layer "F.Fab")
		)
		(fp_line
			(start 0.12065 -0.2794)
			(end 0.12065 -0.3048)
			(stroke
				(width 0.1)
				(type default)
			)
			(layer "F.Fab")
		)
		(fp_line
			(start 0.12065 -0.3048)
			(end 0.67945 -0.3048)
			(stroke
				(width 0.1)
				(type default)
			)
			(layer "F.Fab")
		)
		(fp_line
			(start 0.120396 0.3048)
			(end 0.120396 0.2794)
			(stroke
				(width 0.1)
				(type default)
			)
			(layer "F.Fab")
		)
		(fp_line
			(start 0.120396 0.2794)
			(end -0.12065 0.2794)
			(stroke
				(width 0.1)
				(type default)
			)
			(layer "F.Fab")
		)
		(fp_line
			(start -0.12065 0.3048)
			(end -0.67945 0.3048)
			(stroke
				(width 0.1)
				(type default)
			)
			(layer "F.Fab")
		)
		(fp_line
			(start -0.12065 0.2794)
			(end -0.12065 0.3048)
			(stroke
				(width 0.1)
				(type default)
			)
			(layer "F.Fab")
		)
		(fp_line
			(start -0.12065 -0.2794)
			(end 0.12065 -0.2794)
			(stroke
				(width 0.1)
				(type default)
			)
			(layer "F.Fab")
		)
		(fp_line
			(start -0.12065 -0.305054)
			(end -0.12065 -0.2794)
			(stroke
				(width 0.1)
				(type default)
			)
			(layer "F.Fab")
		)
		(fp_line
			(start -0.67945 0.3048)
			(end -0.67945 -0.305054)
			(stroke
				(width 0.1)
				(type default)
			)
			(layer "F.Fab")
		)
		(fp_line
			(start -0.67945 -0.305054)
			(end -0.12065 -0.305054)
			(stroke
				(width 0.1)
				(type default)
			)
			(layer "F.Fab")
		)
		(pad "1" smd circle
			(at -0.40005 0 180)
			(size 0 0)
			(layers "F.Cu" "F.Mask" "F.Paste")
			(net "RST_PEX_SSD5_PERST_N")
		)
		(pad "2" smd circle
			(at 0.40005 0 180)
			(size 0 0)
			(layers "F.Cu" "F.Mask" "F.Paste")
			(net "RST_PEX_SSD5_PERST_R_N")
		)
	)
	(footprint ""
		(layer "F.Cu")
		(at 288.029142 -116.5352 180)
		(property "Reference" "R244"
			(at 0 0 180)
			(layer "F.SilkS")
			(hide yes)
			(effects
				(font
					(size 1.27 1.27)
				)
			)
		)
		(property "Value" ""
			(at 0 0 180)
			(layer "F.Fab")
			(effects
				(font
					(size 1.27 1.27)
				)
			)
		)
		(duplicate_pad_numbers_are_jumpers no)
		(fp_line
			(start 0.7874 0.4064)
			(end -0.7874 0.4064)
			(stroke
				(width 0.1524)
				(type default)
			)
			(layer "F.SilkS")
		)
		(fp_line
			(start 0.7874 -0.4064)
			(end 0.7874 0.4064)
			(stroke
				(width 0.1524)
				(type default)
			)
			(layer "F.SilkS")
		)
		(fp_line
			(start -0.7874 0.4064)
			(end -0.7874 -0.4064)
			(stroke
				(width 0.1524)
				(type default)
			)
			(layer "F.SilkS")
		)
		(fp_line
			(start -0.7874 -0.4064)
			(end 0.7874 -0.4064)
			(stroke
				(width 0.1524)
				(type default)
			)
			(layer "F.SilkS")
		)
		(fp_line
			(start 0.67945 0.3048)
			(end 0.120396 0.3048)
			(stroke
				(width 0.1)
				(type default)
			)
			(layer "F.Fab")
		)
		(fp_line
			(start 0.67945 -0.3048)
			(end 0.67945 0.3048)
			(stroke
				(width 0.1)
				(type default)
			)
			(layer "F.Fab")
		)
		(fp_line
			(start 0.12065 -0.2794)
			(end 0.12065 -0.3048)
			(stroke
				(width 0.1)
				(type default)
			)
			(layer "F.Fab")
		)
		(fp_line
			(start 0.12065 -0.3048)
			(end 0.67945 -0.3048)
			(stroke
				(width 0.1)
				(type default)
			)
			(layer "F.Fab")
		)
		(fp_line
			(start 0.120396 0.3048)
			(end 0.120396 0.2794)
			(stroke
				(width 0.1)
				(type default)
			)
			(layer "F.Fab")
		)
		(fp_line
			(start 0.120396 0.2794)
			(end -0.12065 0.2794)
			(stroke
				(width 0.1)
				(type default)
			)
			(layer "F.Fab")
		)
		(fp_line
			(start -0.12065 0.3048)
			(end -0.67945 0.3048)
			(stroke
				(width 0.1)
				(type default)
			)
			(layer "F.Fab")
		)
		(fp_line
			(start -0.12065 0.2794)
			(end -0.12065 0.3048)
			(stroke
				(width 0.1)
				(type default)
			)
			(layer "F.Fab")
		)
		(fp_line
			(start -0.12065 -0.2794)
			(end 0.12065 -0.2794)
			(stroke
				(width 0.1)
				(type default)
			)
			(layer "F.Fab")
		)
		(fp_line
			(start -0.12065 -0.305054)
			(end -0.12065 -0.2794)
			(stroke
				(width 0.1)
				(type default)
			)
			(layer "F.Fab")
		)
		(fp_line
			(start -0.67945 0.3048)
			(end -0.67945 -0.305054)
			(stroke
				(width 0.1)
				(type default)
			)
			(layer "F.Fab")
		)
		(fp_line
			(start -0.67945 -0.305054)
			(end -0.12065 -0.305054)
			(stroke
				(width 0.1)
				(type default)
			)
			(layer "F.Fab")
		)
		(pad "1" smd circle
			(at -0.40005 0 180)
			(size 0 0)
			(layers "F.Cu" "F.Mask" "F.Paste")
			(net "PRSNT_NIC4_N")
		)
		(pad "2" smd circle
			(at 0.40005 0 180)
			(size 0 0)
			(layers "F.Cu" "F.Mask" "F.Paste")
			(net "PRSNTB1_NIC4_N")
		)
	)
	(footprint ""
		(layer "F.Cu")
		(at 422.619932 -350.098614 90)
		(property "Reference" "C2452"
			(at 0 0 90)
			(layer "F.SilkS")
			(hide yes)
			(effects
				(font
					(size 1.27 1.27)
				)
			)
		)
		(property "Value" ""
			(at 0 0 90)
			(layer "F.Fab")
			(effects
				(font
					(size 1.27 1.27)
				)
			)
		)
		(duplicate_pad_numbers_are_jumpers no)
		(fp_line
			(start 0.299974 -0.150114)
			(end 0.299974 0.150114)
			(stroke
				(width 0.1)
				(type default)
			)
			(layer "F.Fab")
		)
		(fp_line
			(start -0.299974 -0.150114)
			(end 0.299974 -0.150114)
			(stroke
				(width 0.1)
				(type default)
			)
			(layer "F.Fab")
		)
		(fp_line
			(start 0.299974 0.150114)
			(end -0.299974 0.150114)
			(stroke
				(width 0.1)
				(type default)
			)
			(layer "F.Fab")
		)
		(fp_line
			(start -0.299974 0.150114)
			(end -0.299974 -0.150114)
			(stroke
				(width 0.1)
				(type default)
			)
			(layer "F.Fab")
		)
		(pad "1" smd rect
			(at -0.2667 0 90)
			(size 0.3048 0.381)
			(layers "F.Cu" "F.Mask" "F.Paste")
			(net "P5E_PEX3_STN4_TX_DN<73>")
		)
		(pad "2" smd rect
			(at 0.2667 0 90)
			(size 0.3048 0.381)
			(layers "F.Cu" "F.Mask" "F.Paste")
			(net "P5E_PEX3_STN4_TX_C_DN<73>")
		)
	)
)
